# T6G (Grand Teton) — schematic netlist excerpt (pin names and nets, part order shuffled) for the footprints in the layout excerpt that follows; sources: Cadence DE-HDL packaged netlist, KiCad conversion of 04192023_DAF0TMB3IC0_F0TG_MB_C_brd_V02_OCP.brd

R4303  Q_RES  0 5% CHIP  pkg 0402LF  page 28 : A = CLK_100M_CPU0_CLK12_R_DP ; B = CLK_100M_CPU0_CLK12_DP
PC89_1  Q_CAP  22UF 16V 20% X6S  pkg C0805  page 201 : A = SW_P12V_AUX_PVDDCR_CPU1_P0_FLT ; B = GND

(kicad_pcb
	(version 20260206)
	(generator "pcbnew")
	(generator_version "10.0")
	(general
		(thickness 1.6)
		(legacy_teardrops no)
	)
	(paper "A4")
	(title_block
		(title "04192023_DAF0TMB3IC0_F0TG_MB_C_brd_V02_OCP.brd")
		(comment 1 "Grand Teton / footprints 8273-8275 of 8354")
	)
	(layers
		(0 "F.Cu" signal "TOP")
		(4 "In1.Cu" signal "GND")
		(6 "In2.Cu" signal "IN1")
		(8 "In3.Cu" signal "GND1")
		(10 "In4.Cu" signal "IN2")
		(12 "In5.Cu" signal "GND2")
		(14 "In6.Cu" signal "IN3")
		(16 "In7.Cu" signal "GND3")
		(18 "In8.Cu" signal "VCC")
		(20 "In9.Cu" signal "VCC1")
		(22 "In10.Cu" signal "GND4")
		(24 "In11.Cu" signal "IN4")
		(26 "In12.Cu" signal "GND5")
		(28 "In13.Cu" signal "IN5")
		(30 "In14.Cu" signal "GND6")
		(32 "In15.Cu" signal "IN6")
		(34 "In16.Cu" signal "GND7")
		(2 "B.Cu" signal "BOTTOM")
		(9 "F.Adhes" user "F.Adhesive")
		(11 "B.Adhes" user "B.Adhesive")
		(13 "F.Paste" user "Package Geometry/Pastemask Top")
		(15 "B.Paste" user "Package Geometry/Pastemask Bottom")
		(5 "F.SilkS" user "Ref Des/Silkscreen Top")
		(7 "B.SilkS" user "Ref Des/Silkscreen Bottom")
		(1 "F.Mask" user "Board Geometry/Soldermask Top")
		(3 "B.Mask" user "Board Geometry/Soldermask Bottom")
		(17 "Dwgs.User" user "User.Drawings")
		(19 "Cmts.User" user "User.Comments")
		(21 "Eco1.User" user "User.Eco1")
		(23 "Eco2.User" user "User.Eco2")
		(25 "Edge.Cuts" user "Board Geometry/Outline")
		(27 "Margin" user)
		(31 "F.CrtYd" user "Package Geometry/Place Bound Top")
		(29 "B.CrtYd" user "Package Geometry/Place Bound Bottom")
		(35 "F.Fab" user "Ref Des/Assembly Top")
		(33 "B.Fab" user "Ref Des/Assembly Bottom")
	)
	(footprint ""
		(layer "B.Cu")
		(at 343.514934 -301.911258 -90)
		(property "Reference" "R4303"
			(at 0 0 90)
			(layer "B.SilkS")
			(hide yes)
			(effects
				(font
					(size 1.27 1.27)
				)
				(justify mirror)
			)
		)
		(property "Value" ""
			(at 0 0 90)
			(layer "B.Fab")
			(effects
				(font
					(size 1.27 1.27)
				)
				(justify mirror)
			)
		)
		(duplicate_pad_numbers_are_jumpers no)
		(fp_line
			(start -0.374142 0.4064)
			(end 0.311658 0.4064)
			(stroke
				(width 0.1524)
				(type default)
			)
			(layer "B.SilkS")
		)
		(fp_line
			(start 0.7874 0.005334)
			(end 0.7874 -0.4064)
			(stroke
				(width 0.1524)
				(type default)
			)
			(layer "B.SilkS")
		)
		(fp_line
			(start -0.7874 -0.4064)
			(end -0.7874 0.005334)
			(stroke
				(width 0.1524)
				(type default)
			)
			(layer "B.SilkS")
		)
		(fp_line
			(start 0.7874 -0.4064)
			(end -0.7874 -0.4064)
			(stroke
				(width 0.1524)
				(type default)
			)
			(layer "B.SilkS")
		)
		(fp_line
			(start -0.67945 0.3048)
			(end -0.120396 0.3048)
			(stroke
				(width 0.1)
				(type default)
			)
			(layer "B.Fab")
		)
		(fp_line
			(start -0.120396 0.3048)
			(end -0.120396 0.2794)
			(stroke
				(width 0.1)
				(type default)
			)
			(layer "B.Fab")
		)
		(fp_line
			(start 0.12065 0.3048)
			(end 0.67945 0.3048)
			(stroke
				(width 0.1)
				(type default)
			)
			(layer "B.Fab")
		)
		(fp_line
			(start 0.67945 0.3048)
			(end 0.67945 -0.305054)
			(stroke
				(width 0.1)
				(type default)
			)
			(layer "B.Fab")
		)
		(fp_line
			(start -0.120396 0.2794)
			(end 0.12065 0.2794)
			(stroke
				(width 0.1)
				(type default)
			)
			(layer "B.Fab")
		)
		(fp_line
			(start 0.12065 0.2794)
			(end 0.12065 0.3048)
			(stroke
				(width 0.1)
				(type default)
			)
			(layer "B.Fab")
		)
		(fp_line
			(start -0.12065 -0.2794)
			(end -0.12065 -0.3048)
			(stroke
				(width 0.1)
				(type default)
			)
			(layer "B.Fab")
		)
		(fp_line
			(start 0.12065 -0.2794)
			(end -0.12065 -0.2794)
			(stroke
				(width 0.1)
				(type default)
			)
			(layer "B.Fab")
		)
		(fp_line
			(start -0.67945 -0.3048)
			(end -0.67945 0.3048)
			(stroke
				(width 0.1)
				(type default)
			)
			(layer "B.Fab")
		)
		(fp_line
			(start -0.12065 -0.3048)
			(end -0.67945 -0.3048)
			(stroke
				(width 0.1)
				(type default)
			)
			(layer "B.Fab")
		)
		(fp_line
			(start 0.12065 -0.305054)
			(end 0.12065 -0.2794)
			(stroke
				(width 0.1)
				(type default)
			)
			(layer "B.Fab")
		)
		(fp_line
			(start 0.67945 -0.305054)
			(end 0.12065 -0.305054)
			(stroke
				(width 0.1)
				(type default)
			)
			(layer "B.Fab")
		)
		(pad "1" smd circle
			(at 0.40005 0 90)
			(size 0 0)
			(layers "B.Cu" "B.Mask" "B.Paste")
			(net "CLK_100M_CPU0_CLK12_R_DP")
		)
		(pad "2" smd circle
			(at -0.40005 0 90)
			(size 0 0)
			(layers "B.Cu" "B.Mask" "B.Paste")
			(net "CLK_100M_CPU0_CLK12_DP")
		)
	)
	(footprint ""
		(layer "B.Cu")
		(at 396.696184 -385.529328)
		(property "Reference" "ME8"
			(at 0 0 0)
			(layer "B.SilkS")
			(hide yes)
			(effects
				(font
					(size 1.27 1.27)
				)
				(justify mirror)
			)
		)
		(property "Value" ""
			(at 0 0 0)
			(layer "B.Fab")
			(effects
				(font
					(size 1.27 1.27)
				)
				(justify mirror)
			)
		)
		(duplicate_pad_numbers_are_jumpers no)
		(zone
			(layer "B.Cu")
			(hatch none 0.5)
			(connect_pads
				(clearance 0)
			)
			(min_thickness 0.25)
			(keepout
				(tracks allowed)
				(vias allowed)
				(pads allowed)
				(copperpour allowed)
				(footprints not_allowed)
			)
			(placement
				(enabled no)
				(sheetname "")
			)
			(fill
				(thermal_gap 0.5)
				(thermal_bridge_width 0.5)
				(island_removal_mode 0)
			)
			(polygon
				(pts
					(arc
						(start 464.0199 -364.816136)
						(mid 444.01994 -364.816136)
						(end 464.0199 -364.816136)
					)
				)
			)
		)
	)
	(footprint ""
		(layer "B.Cu")
		(at 336.180684 -335.041494 90)
		(property "Reference" "PC89_1"
			(at 0 0 90)
			(layer "B.SilkS")
			(hide yes)
			(effects
				(font
					(size 1.27 1.27)
				)
				(justify mirror)
			)
		)
		(property "Value" ""
			(at 0 0 90)
			(layer "B.Fab")
			(effects
				(font
					(size 1.27 1.27)
				)
				(justify mirror)
			)
		)
		(duplicate_pad_numbers_are_jumpers no)
		(fp_line
			(start 1.524 -0.762)
			(end -1.524 -0.762)
			(stroke
				(width 0.1524)
				(type default)
			)
			(layer "B.SilkS")
		)
		(fp_line
			(start -1.524 -0.762)
			(end -1.524 0.762)
			(stroke
				(width 0.1524)
				(type default)
			)
			(layer "B.SilkS")
		)
		(fp_line
			(start 1.524 0.762)
			(end 1.524 -0.762)
			(stroke
				(width 0.1524)
				(type default)
			)
			(layer "B.SilkS")
		)
		(fp_line
			(start -1.524 0.762)
			(end 1.524 0.762)
			(stroke
				(width 0.1524)
				(type default)
			)
			(layer "B.SilkS")
		)
		(fp_line
			(start 1.1049 -0.724916)
			(end 1.1049 0.724916)
			(stroke
				(width 0.1)
				(type default)
			)
			(layer "B.Fab")
		)
		(fp_line
			(start -1.1049 -0.724916)
			(end 1.1049 -0.724916)
			(stroke
				(width 0.1)
				(type default)
			)
			(layer "B.Fab")
		)
		(fp_line
			(start 1.1049 0.724916)
			(end -1.1049 0.724916)
			(stroke
				(width 0.1)
				(type default)
			)
			(layer "B.Fab")
		)
		(fp_line
			(start -1.1049 0.724916)
			(end -1.1049 -0.724916)
			(stroke
				(width 0.1)
				(type default)
			)
			(layer "B.Fab")
		)
		(pad "1" smd rect
			(at 0.889 0 90)
			(size 1.016 1.27)
			(layers "B.Cu" "B.Mask" "B.Paste")
			(net "SW_P12V_AUX_PVDDCR_CPU1_P0_FLT")
		)
		(pad "2" smd rect
			(at -0.889 0 90)
			(size 1.016 1.27)
			(layers "B.Cu" "B.Mask" "B.Paste")
			(net "GND")
		)
	)
)
